# BASEBOARD_FAB2 (Tioga Pass) — schematic netlist excerpt (pin names and nets, part order shuffled) for the footprints in the layout excerpt that follows; sources: Cadence DE-HDL packaged netlist, KiCad conversion of Wiwynn_Tioga_Pass_MB.brd

R25W120  RES  0 5.0% CHIP  pkg 0603  page 149 : A = P3V3_STBY ; B = P3V3_USB2A_ALG
R6T5  RES  1.00K 1% CHIP  pkg 0402  page 112 : A = XDP_CPU_TRST_N ; B = GND
C22W27  SC22U16V5MX-4-GP  20%  pkg SMD-BCG5  page 236 : \1\ = VR_FET_SW_P12V_STBY_PVDDQ_DEF ; \2\ = GND

(kicad_pcb
	(version 20260206)
	(generator "pcbnew")
	(generator_version "10.0")
	(general
		(thickness 1.6)
		(legacy_teardrops no)
	)
	(paper "A4")
	(title_block
		(title "Wiwynn_Tioga_Pass_MB.brd")
		(comment 1 "Tioga Pass / footprints 4091-4093 of 4770")
	)
	(layers
		(0 "F.Cu" signal "TOP")
		(4 "In1.Cu" signal "L2GND")
		(6 "In2.Cu" signal "L3")
		(8 "In3.Cu" signal "L4GND")
		(10 "In4.Cu" signal "L5")
		(12 "In5.Cu" signal "L6GND")
		(14 "In6.Cu" signal "L7VCC")
		(16 "In7.Cu" signal "L8VCC")
		(18 "In8.Cu" signal "L9GND")
		(20 "In9.Cu" signal "L10")
		(22 "In10.Cu" signal "L11GND")
		(24 "In11.Cu" signal "L12")
		(26 "In12.Cu" signal "L13GND")
		(2 "B.Cu" signal "BOTTOM")
		(9 "F.Adhes" user "F.Adhesive")
		(11 "B.Adhes" user "B.Adhesive")
		(13 "F.Paste" user "Package Geometry/Pastemask Top")
		(15 "B.Paste" user "Package Geometry/Pastemask Bottom")
		(5 "F.SilkS" user "Ref Des/Silkscreen Top")
		(7 "B.SilkS" user "Ref Des/Silkscreen Bottom")
		(1 "F.Mask" user "Board Geometry/Soldermask Top")
		(3 "B.Mask" user "Board Geometry/Soldermask Bottom")
		(17 "Dwgs.User" user "User.Drawings")
		(19 "Cmts.User" user "User.Comments")
		(21 "Eco1.User" user "User.Eco1")
		(23 "Eco2.User" user "User.Eco2")
		(25 "Edge.Cuts" user "Board Geometry/Outline")
		(27 "Margin" user)
		(31 "F.CrtYd" user "Package Geometry/Place Bound Top")
		(29 "B.CrtYd" user "Package Geometry/Place Bound Bottom")
		(35 "F.Fab" user "Ref Des/Assembly Top")
		(33 "B.Fab" user "Ref Des/Assembly Bottom")
	)
	(footprint ""
		(layer "B.Cu")
		(at 402.606256 -29.603446 180)
		(property "Reference" "R25W120"
			(at -1.01473 0.656336 270)
			(unlocked yes)
			(layer "B.SilkS")
			(effects
				(font
					(size 0.4064 0.254)
					(thickness 0.1524)
				)
				(justify mirror)
			)
		)
		(property "Value" ""
			(at 0 0 0)
			(layer "B.Fab")
			(effects
				(font
					(size 1.27 1.27)
				)
				(justify mirror)
			)
		)
		(duplicate_pad_numbers_are_jumpers no)
		(fp_poly
			(pts
				(xy 0.4953 -0.2032) (xy -0.4953 -0.2032) (xy -0.4953 1.6002) (xy 0.4953 1.6002)
			)
			(stroke
				(width 0)
				(type default)
			)
			(fill no)
			(layer "B.CrtYd")
		)
		(fp_line
			(start 0.4953 1.6002)
			(end 0.4953 -0.2032)
			(stroke
				(width 0.1)
				(type default)
			)
			(layer "B.Fab")
		)
		(fp_line
			(start 0.4953 -0.2032)
			(end -0.4953 -0.2032)
			(stroke
				(width 0.1)
				(type default)
			)
			(layer "B.Fab")
		)
		(fp_line
			(start -0.4953 1.6002)
			(end 0.4953 1.6002)
			(stroke
				(width 0.1)
				(type default)
			)
			(layer "B.Fab")
		)
		(fp_line
			(start -0.4953 -0.2032)
			(end -0.4953 1.6002)
			(stroke
				(width 0.1)
				(type default)
			)
			(layer "B.Fab")
		)
		(pad "1" smd rect
			(at 0 0)
			(size 0.762 0.889)
			(layers "B.Cu" "B.Mask" "B.Paste")
			(net "P3V3_STBY")
		)
		(pad "2" smd rect
			(at 0 1.397)
			(size 0.762 0.889)
			(layers "B.Cu" "B.Mask" "B.Paste")
			(net "P3V3_USB2A_ALG")
		)
		(zone
			(layer "B.Cu")
			(hatch none 0.5)
			(connect_pads
				(clearance 0)
			)
			(min_thickness 0.25)
			(keepout
				(tracks not_allowed)
				(vias allowed)
				(pads allowed)
				(copperpour not_allowed)
				(footprints allowed)
			)
			(placement
				(enabled no)
				(sheetname "")
			)
			(fill
				(thermal_gap 0.5)
				(thermal_bridge_width 0.5)
				(island_removal_mode 0)
			)
			(polygon
				(pts
					(xy 402.225256 -30.555946) (xy 402.225256 -30.047946) (xy 402.987256 -30.047946) (xy 402.987256 -30.555946)
				)
			)
		)
		(zone
			(layer "B.Cu")
			(hatch none 0.5)
			(connect_pads
				(clearance 0)
			)
			(min_thickness 0.25)
			(keepout
				(tracks allowed)
				(vias not_allowed)
				(pads allowed)
				(copperpour not_allowed)
				(footprints allowed)
			)
			(placement
				(enabled no)
				(sheetname "")
			)
			(fill
				(thermal_gap 0.5)
				(thermal_bridge_width 0.5)
				(island_removal_mode 0)
			)
			(polygon
				(pts
					(xy 402.987256 -30.555946) (xy 402.987256 -30.047946) (xy 402.225256 -30.047946) (xy 402.225256 -30.555946)
				)
			)
		)
	)
	(footprint ""
		(layer "B.Cu")
		(at 367.968276 -156.15158 180)
		(property "Reference" "C22W27"
			(at 0 0 0)
			(layer "B.SilkS")
			(hide yes)
			(effects
				(font
					(size 1.27 1.27)
				)
				(justify mirror)
			)
		)
		(property "Value" "*"
			(at 0.0762 -6.2357 180)
			(unlocked yes)
			(layer "B.Fab")
			(hide yes)
			(effects
				(font
					(size 1.27 1.016)
					(thickness 0.1524)
				)
				(justify mirror)
			)
		)
		(property "Device Type" "SC22U16V5MX-4-GP_SMD-BCG5-SC22A"
			(at 0.0762 -8.2677 180)
			(unlocked yes)
			(layer "B.Fab")
			(hide yes)
			(effects
				(font
					(size 1.27 1.016)
					(thickness 0.1524)
				)
				(justify mirror)
			)
		)
		(duplicate_pad_numbers_are_jumpers no)
		(fp_line
			(start -0.635 0)
			(end 0.635 0)
			(stroke
				(width 0.508)
				(type default)
			)
			(layer "B.SilkS")
		)
		(fp_rect
			(start 0.9652 1.778)
			(end -0.9652 -1.778)
			(stroke
				(width 0)
				(type default)
			)
			(fill no)
			(layer "B.CrtYd")
		)
		(fp_poly
			(pts
				(xy 0.9652 -1.778) (xy -0.9652 -1.778) (xy -0.9652 1.778) (xy 0.9652 1.778)
			)
			(stroke
				(width 0)
				(type default)
			)
			(fill no)
			(layer "B.Fab")
		)
		(pad "1" smd rect
			(at 0 -0.9652)
			(size 1.397 1.143)
			(layers "B.Cu" "B.Mask" "B.Paste")
			(net "VR_FET_SW_P12V_STBY_PVDDQ_DEF")
		)
		(pad "2" smd rect
			(at 0 0.9652)
			(size 1.397 1.143)
			(layers "B.Cu" "B.Mask" "B.Paste")
			(net "GND")
		)
	)
	(footprint ""
		(layer "B.Cu")
		(at 176.276 -20.193)
		(property "Reference" "R6T5"
			(at 0 0 0)
			(layer "B.SilkS")
			(hide yes)
			(effects
				(font
					(size 1.27 1.27)
				)
				(justify mirror)
			)
		)
		(property "Value" ""
			(at 0 0 0)
			(layer "B.Fab")
			(effects
				(font
					(size 1.27 1.27)
				)
				(justify mirror)
			)
		)
		(duplicate_pad_numbers_are_jumpers no)
		(fp_poly
			(pts
				(xy 0.2794 -0.1016) (xy -0.2794 -0.1016) (xy -0.2794 0.9906) (xy 0.2794 0.9906)
			)
			(stroke
				(width 0)
				(type default)
			)
			(fill no)
			(layer "B.CrtYd")
		)
		(fp_line
			(start -0.2794 -0.1016)
			(end 0.2794 -0.1016)
			(stroke
				(width 0.1)
				(type default)
			)
			(layer "B.Fab")
		)
		(fp_line
			(start -0.2794 0.9906)
			(end -0.2794 -0.1016)
			(stroke
				(width 0.1)
				(type default)
			)
			(layer "B.Fab")
		)
		(fp_line
			(start 0.2794 -0.1016)
			(end 0.2794 0.9906)
			(stroke
				(width 0.1)
				(type default)
			)
			(layer "B.Fab")
		)
		(fp_line
			(start 0.2794 0.9906)
			(end -0.2794 0.9906)
			(stroke
				(width 0.1)
				(type default)
			)
			(layer "B.Fab")
		)
		(pad "1" smd rect
			(at 0 0 180)
			(size 0.508 0.508)
			(layers "B.Cu" "B.Mask" "B.Paste")
			(net "XDP_CPU_TRST_N")
		)
		(pad "2" smd rect
			(at 0 0.889 180)
			(size 0.508 0.508)
			(layers "B.Cu" "B.Mask" "B.Paste")
			(net "GND")
		)
		(zone
			(layer "B.Cu")
			(hatch none 0.5)
			(connect_pads
				(clearance 0)
			)
			(min_thickness 0.25)
			(keepout
				(tracks allowed)
				(vias not_allowed)
				(pads allowed)
				(copperpour not_allowed)
				(footprints allowed)
			)
			(placement
				(enabled no)
				(sheetname "")
			)
			(fill
				(thermal_gap 0.5)
				(thermal_bridge_width 0.5)
				(island_removal_mode 0)
			)
			(polygon
				(pts
					(xy 176.53 -19.939) (xy 176.022 -19.939) (xy 176.022 -19.558) (xy 176.53 -19.558)
				)
			)
		)
		(zone
			(layer "B.Cu")
			(hatch none 0.5)
			(connect_pads
				(clearance 0)
			)
			(min_thickness 0.25)
			(keepout
				(tracks not_allowed)
				(vias allowed)
				(pads allowed)
				(copperpour not_allowed)
				(footprints allowed)
			)
			(placement
				(enabled no)
				(sheetname "")
			)
			(fill
				(thermal_gap 0.5)
				(thermal_bridge_width 0.5)
				(island_removal_mode 0)
			)
			(polygon
				(pts
					(xy 176.53 -19.558) (xy 176.022 -19.558) (xy 176.022 -19.939) (xy 176.53 -19.939)
				)
			)
		)
	)
)
